(kicad_pcb
	(version 20260206)
	(generator "pcbnew")
	(generator_version "10.0")
	(general
		(thickness 1.6)
		(legacy_teardrops no)
	)
	(paper "A4")
	(title_block
		(title "12092022_DA0F0TMDCD0_F0T_Management_Board_D_brd_V3_OCP.brd")
		(comment 1 "Grand Teton / footprints 366-371 of 1440")
	)
	(layers
		(0 "F.Cu" signal "TOP")
		(4 "In1.Cu" signal "GND")
		(6 "In2.Cu" signal "IN1")
		(8 "In3.Cu" signal "GND1")
		(10 "In4.Cu" signal "IN2")
		(12 "In5.Cu" signal "VCC")
		(14 "In6.Cu" signal "VCC1")
		(16 "In7.Cu" signal "IN3")
		(18 "In8.Cu" signal "GND2")
		(20 "In9.Cu" signal "IN4")
		(22 "In10.Cu" signal "GND3")
		(2 "B.Cu" signal "BOTTOM")
		(9 "F.Adhes" user "F.Adhesive")
		(11 "B.Adhes" user "B.Adhesive")
		(13 "F.Paste" user "Package Geometry/Pastemask Top")
		(15 "B.Paste" user "Package Geometry/Pastemask Bottom")
		(5 "F.SilkS" user "Ref Des/Silkscreen Top")
		(7 "B.SilkS" user "Ref Des/Silkscreen Bottom")
		(1 "F.Mask" user "Board Geometry/Soldermask Top")
		(3 "B.Mask" user "Board Geometry/Soldermask Bottom")
		(17 "Dwgs.User" user "User.Drawings")
		(19 "Cmts.User" user "User.Comments")
		(21 "Eco1.User" user "User.Eco1")
		(23 "Eco2.User" user "User.Eco2")
		(25 "Edge.Cuts" user "Board Geometry/Outline")
		(27 "Margin" user)
		(31 "F.CrtYd" user "Package Geometry/Place Bound Top")
		(29 "B.CrtYd" user "Package Geometry/Place Bound Bottom")
		(35 "F.Fab" user "Ref Des/Assembly Top")
		(33 "B.Fab" user "Ref Des/Assembly Bottom")
	)
	(footprint ""
		(layer "F.Cu")
		(at 57.18302 -97.34804)
		(property "Reference" "R136"
			(at 0 0 0)
			(layer "F.SilkS")
			(hide yes)
			(effects
				(font
					(size 1.27 1.27)
				)
			)
		)
		(property "Value" ""
			(at 0 0 0)
			(layer "F.Fab")
			(effects
				(font
					(size 1.27 1.27)
				)
			)
		)
		(duplicate_pad_numbers_are_jumpers no)
		(fp_line
			(start -0.7874 -0.4064)
			(end 0.7874 -0.4064)
			(stroke
				(width 0.1524)
				(type default)
			)
			(layer "F.SilkS")
		)
		(fp_line
			(start -0.7874 0.4064)
			(end -0.7874 -0.4064)
			(stroke
				(width 0.1524)
				(type default)
			)
			(layer "F.SilkS")
		)
		(fp_line
			(start 0.7874 -0.4064)
			(end 0.7874 0.4064)
			(stroke
				(width 0.1524)
				(type default)
			)
			(layer "F.SilkS")
		)
		(fp_line
			(start 0.7874 0.4064)
			(end -0.7874 0.4064)
			(stroke
				(width 0.1524)
				(type default)
			)
			(layer "F.SilkS")
		)
		(fp_line
			(start -0.67945 -0.305054)
			(end -0.12065 -0.305054)
			(stroke
				(width 0.1)
				(type default)
			)
			(layer "F.Fab")
		)
		(fp_line
			(start -0.67945 0.3048)
			(end -0.67945 -0.305054)
			(stroke
				(width 0.1)
				(type default)
			)
			(layer "F.Fab")
		)
		(fp_line
			(start -0.12065 -0.305054)
			(end -0.12065 -0.2794)
			(stroke
				(width 0.1)
				(type default)
			)
			(layer "F.Fab")
		)
		(fp_line
			(start -0.12065 -0.2794)
			(end 0.12065 -0.2794)
			(stroke
				(width 0.1)
				(type default)
			)
			(layer "F.Fab")
		)
		(fp_line
			(start -0.12065 0.2794)
			(end -0.12065 0.3048)
			(stroke
				(width 0.1)
				(type default)
			)
			(layer "F.Fab")
		)
		(fp_line
			(start -0.12065 0.3048)
			(end -0.67945 0.3048)
			(stroke
				(width 0.1)
				(type default)
			)
			(layer "F.Fab")
		)
		(fp_line
			(start 0.120396 0.2794)
			(end -0.12065 0.2794)
			(stroke
				(width 0.1)
				(type default)
			)
			(layer "F.Fab")
		)
		(fp_line
			(start 0.120396 0.3048)
			(end 0.120396 0.2794)
			(stroke
				(width 0.1)
				(type default)
			)
			(layer "F.Fab")
		)
		(fp_line
			(start 0.12065 -0.3048)
			(end 0.67945 -0.3048)
			(stroke
				(width 0.1)
				(type default)
			)
			(layer "F.Fab")
		)
		(fp_line
			(start 0.12065 -0.2794)
			(end 0.12065 -0.3048)
			(stroke
				(width 0.1)
				(type default)
			)
			(layer "F.Fab")
		)
		(fp_line
			(start 0.67945 -0.3048)
			(end 0.67945 0.3048)
			(stroke
				(width 0.1)
				(type default)
			)
			(layer "F.Fab")
		)
		(fp_line
			(start 0.67945 0.3048)
			(end 0.120396 0.3048)
			(stroke
				(width 0.1)
				(type default)
			)
			(layer "F.Fab")
		)
		(pad "1" smd circle
			(at -0.40005 0)
			(size 0 0)
			(layers "F.Cu" "F.Mask" "F.Paste")
			(net "P3V3_AUX")
		)
		(pad "2" smd circle
			(at 0.40005 0)
			(size 0 0)
			(layers "F.Cu" "F.Mask" "F.Paste")
			(net "SMB_PCH_TPM_SCL")
		)
	)
	(footprint ""
		(layer "F.Cu")
		(at 43.171618 -65.776094 -90)
		(property "Reference" "R187"
			(at 0 0 270)
			(layer "F.SilkS")
			(hide yes)
			(effects
				(font
					(size 1.27 1.27)
				)
			)
		)
		(property "Value" ""
			(at 0 0 270)
			(layer "F.Fab")
			(effects
				(font
					(size 1.27 1.27)
				)
			)
		)
		(duplicate_pad_numbers_are_jumpers no)
		(fp_line
			(start -0.7874 0.4064)
			(end -0.7874 -0.4064)
			(stroke
				(width 0.1524)
				(type default)
			)
			(layer "F.SilkS")
		)
		(fp_line
			(start 0.7874 0.4064)
			(end -0.7874 0.4064)
			(stroke
				(width 0.1524)
				(type default)
			)
			(layer "F.SilkS")
		)
		(fp_line
			(start -0.7874 -0.4064)
			(end 0.7874 -0.4064)
			(stroke
				(width 0.1524)
				(type default)
			)
			(layer "F.SilkS")
		)
		(fp_line
			(start 0.7874 -0.4064)
			(end 0.7874 0.4064)
			(stroke
				(width 0.1524)
				(type default)
			)
			(layer "F.SilkS")
		)
		(fp_line
			(start -0.67945 0.3048)
			(end -0.67945 -0.305054)
			(stroke
				(width 0.1)
				(type default)
			)
			(layer "F.Fab")
		)
		(fp_line
			(start -0.12065 0.3048)
			(end -0.67945 0.3048)
			(stroke
				(width 0.1)
				(type default)
			)
			(layer "F.Fab")
		)
		(fp_line
			(start 0.120396 0.3048)
			(end 0.120396 0.2794)
			(stroke
				(width 0.1)
				(type default)
			)
			(layer "F.Fab")
		)
		(fp_line
			(start 0.67945 0.3048)
			(end 0.120396 0.3048)
			(stroke
				(width 0.1)
				(type default)
			)
			(layer "F.Fab")
		)
		(fp_line
			(start -0.12065 0.2794)
			(end -0.12065 0.3048)
			(stroke
				(width 0.1)
				(type default)
			)
			(layer "F.Fab")
		)
		(fp_line
			(start 0.120396 0.2794)
			(end -0.12065 0.2794)
			(stroke
				(width 0.1)
				(type default)
			)
			(layer "F.Fab")
		)
		(fp_line
			(start -0.12065 -0.2794)
			(end 0.12065 -0.2794)
			(stroke
				(width 0.1)
				(type default)
			)
			(layer "F.Fab")
		)
		(fp_line
			(start 0.12065 -0.2794)
			(end 0.12065 -0.3048)
			(stroke
				(width 0.1)
				(type default)
			)
			(layer "F.Fab")
		)
		(fp_line
			(start 0.12065 -0.3048)
			(end 0.67945 -0.3048)
			(stroke
				(width 0.1)
				(type default)
			)
			(layer "F.Fab")
		)
		(fp_line
			(start 0.67945 -0.3048)
			(end 0.67945 0.3048)
			(stroke
				(width 0.1)
				(type default)
			)
			(layer "F.Fab")
		)
		(fp_line
			(start -0.67945 -0.305054)
			(end -0.12065 -0.305054)
			(stroke
				(width 0.1)
				(type default)
			)
			(layer "F.Fab")
		)
		(fp_line
			(start -0.12065 -0.305054)
			(end -0.12065 -0.2794)
			(stroke
				(width 0.1)
				(type default)
			)
			(layer "F.Fab")
		)
		(pad "1" smd circle
			(at -0.40005 0 270)
			(size 0 0)
			(layers "F.Cu" "F.Mask" "F.Paste")
			(net "I3C2_SPD_SDA")
		)
		(pad "2" smd circle
			(at 0.40005 0 270)
			(size 0 0)
			(layers "F.Cu" "F.Mask" "F.Paste")
			(net "I3C2_SDA_R")
		)
	)
	(footprint ""
		(layer "F.Cu")
		(at 6.715252 -78.19009 90)
		(property "Reference" "PC227"
			(at 0 0 90)
			(layer "F.SilkS")
			(hide yes)
			(effects
				(font
					(size 1.27 1.27)
				)
			)
		)
		(property "Value" ""
			(at 0 0 90)
			(layer "F.Fab")
			(effects
				(font
					(size 1.27 1.27)
				)
			)
		)
		(duplicate_pad_numbers_are_jumpers no)
		(fp_line
			(start 1.651 -0.8382)
			(end 1.651 0.8382)
			(stroke
				(width 0.1524)
				(type default)
			)
			(layer "F.SilkS")
		)
		(fp_line
			(start -1.651 -0.8382)
			(end 1.651 -0.8382)
			(stroke
				(width 0.1524)
				(type default)
			)
			(layer "F.SilkS")
		)
		(fp_line
			(start 1.651 0.8382)
			(end -1.651 0.8382)
			(stroke
				(width 0.1524)
				(type default)
			)
			(layer "F.SilkS")
		)
		(fp_line
			(start 0 0.8382)
			(end 0 -0.8382)
			(stroke
				(width 0.1524)
				(type default)
			)
			(layer "F.SilkS")
		)
		(fp_line
			(start -1.651 0.8382)
			(end -1.651 -0.8382)
			(stroke
				(width 0.1524)
				(type default)
			)
			(layer "F.SilkS")
		)
		(fp_line
			(start 1.55956 -0.7366)
			(end 1.524 -0.7366)
			(stroke
				(width 0.1)
				(type default)
			)
			(layer "F.Fab")
		)
		(fp_line
			(start 1.524 -0.7366)
			(end -1.524 -0.7366)
			(stroke
				(width 0.1)
				(type default)
			)
			(layer "F.Fab")
		)
		(fp_line
			(start -1.524 -0.7366)
			(end -1.55956 -0.7366)
			(stroke
				(width 0.1)
				(type default)
			)
			(layer "F.Fab")
		)
		(fp_line
			(start -1.55956 -0.7366)
			(end -1.55956 0.7366)
			(stroke
				(width 0.1)
				(type default)
			)
			(layer "F.Fab")
		)
		(fp_line
			(start 1.55956 0.7366)
			(end 1.55956 -0.7366)
			(stroke
				(width 0.1)
				(type default)
			)
			(layer "F.Fab")
		)
		(fp_line
			(start 1.524 0.7366)
			(end 1.55956 0.7366)
			(stroke
				(width 0.1)
				(type default)
			)
			(layer "F.Fab")
		)
		(fp_line
			(start -1.524 0.7366)
			(end 1.524 0.7366)
			(stroke
				(width 0.1)
				(type default)
			)
			(layer "F.Fab")
		)
		(fp_line
			(start -1.55956 0.7366)
			(end -1.524 0.7366)
			(stroke
				(width 0.1)
				(type default)
			)
			(layer "F.Fab")
		)
		(pad "1" smd rect
			(at -0.94996 0 270)
			(size 1.1176 1.3716)
			(layers "F.Cu" "F.Mask" "F.Paste")
			(net "P3V3_AUX")
		)
		(pad "2" smd rect
			(at 0.94996 0 270)
			(size 1.1176 1.3716)
			(layers "F.Cu" "F.Mask" "F.Paste")
			(net "GND")
		)
	)
	(footprint ""
		(layer "F.Cu")
		(at 34.015172 -83.816952 90)
		(property "Reference" "R647"
			(at 0 0 90)
			(layer "F.SilkS")
			(hide yes)
			(effects
				(font
					(size 1.27 1.27)
				)
			)
		)
		(property "Value" ""
			(at 0 0 90)
			(layer "F.Fab")
			(effects
				(font
					(size 1.27 1.27)
				)
			)
		)
		(duplicate_pad_numbers_are_jumpers no)
		(fp_line
			(start 0.7874 -0.4064)
			(end 0.7874 0.4064)
			(stroke
				(width 0.1524)
				(type default)
			)
			(layer "F.SilkS")
		)
		(fp_line
			(start -0.7874 -0.4064)
			(end 0.7874 -0.4064)
			(stroke
				(width 0.1524)
				(type default)
			)
			(layer "F.SilkS")
		)
		(fp_line
			(start 0.7874 0.4064)
			(end -0.7874 0.4064)
			(stroke
				(width 0.1524)
				(type default)
			)
			(layer "F.SilkS")
		)
		(fp_line
			(start -0.7874 0.4064)
			(end -0.7874 -0.4064)
			(stroke
				(width 0.1524)
				(type default)
			)
			(layer "F.SilkS")
		)
		(fp_line
			(start -0.12065 -0.305054)
			(end -0.12065 -0.2794)
			(stroke
				(width 0.1)
				(type default)
			)
			(layer "F.Fab")
		)
		(fp_line
			(start -0.67945 -0.305054)
			(end -0.12065 -0.305054)
			(stroke
				(width 0.1)
				(type default)
			)
			(layer "F.Fab")
		)
		(fp_line
			(start 0.67945 -0.3048)
			(end 0.67945 0.3048)
			(stroke
				(width 0.1)
				(type default)
			)
			(layer "F.Fab")
		)
		(fp_line
			(start 0.12065 -0.3048)
			(end 0.67945 -0.3048)
			(stroke
				(width 0.1)
				(type default)
			)
			(layer "F.Fab")
		)
		(fp_line
			(start 0.12065 -0.2794)
			(end 0.12065 -0.3048)
			(stroke
				(width 0.1)
				(type default)
			)
			(layer "F.Fab")
		)
		(fp_line
			(start -0.12065 -0.2794)
			(end 0.12065 -0.2794)
			(stroke
				(width 0.1)
				(type default)
			)
			(layer "F.Fab")
		)
		(fp_line
			(start 0.120396 0.2794)
			(end -0.12065 0.2794)
			(stroke
				(width 0.1)
				(type default)
			)
			(layer "F.Fab")
		)
		(fp_line
			(start -0.12065 0.2794)
			(end -0.12065 0.3048)
			(stroke
				(width 0.1)
				(type default)
			)
			(layer "F.Fab")
		)
		(fp_line
			(start 0.67945 0.3048)
			(end 0.120396 0.3048)
			(stroke
				(width 0.1)
				(type default)
			)
			(layer "F.Fab")
		)
		(fp_line
			(start 0.120396 0.3048)
			(end 0.120396 0.2794)
			(stroke
				(width 0.1)
				(type default)
			)
			(layer "F.Fab")
		)
		(fp_line
			(start -0.12065 0.3048)
			(end -0.67945 0.3048)
			(stroke
				(width 0.1)
				(type default)
			)
			(layer "F.Fab")
		)
		(fp_line
			(start -0.67945 0.3048)
			(end -0.67945 -0.305054)
			(stroke
				(width 0.1)
				(type default)
			)
			(layer "F.Fab")
		)
		(pad "1" smd circle
			(at -0.40005 0 90)
			(size 0 0)
			(layers "F.Cu" "F.Mask" "F.Paste")
			(net "EMMC_DT2_R")
		)
		(pad "2" smd circle
			(at 0.40005 0 90)
			(size 0 0)
			(layers "F.Cu" "F.Mask" "F.Paste")
			(net "BMC_EMMC_DT2")
		)
	)
	(footprint ""
		(layer "F.Cu")
		(at 71.4375 -29.845 -90)
		(property "Reference" "R99"
			(at 0 0 270)
			(layer "F.SilkS")
			(hide yes)
			(effects
				(font
					(size 1.27 1.27)
				)
			)
		)
		(property "Value" ""
			(at 0 0 270)
			(layer "F.Fab")
			(effects
				(font
					(size 1.27 1.27)
				)
			)
		)
		(duplicate_pad_numbers_are_jumpers no)
		(fp_line
			(start -0.7874 0.4064)
			(end -0.7874 -0.4064)
			(stroke
				(width 0.1524)
				(type default)
			)
			(layer "F.SilkS")
		)
		(fp_line
			(start 0.7874 0.4064)
			(end -0.7874 0.4064)
			(stroke
				(width 0.1524)
				(type default)
			)
			(layer "F.SilkS")
		)
		(fp_line
			(start -0.7874 -0.4064)
			(end 0.7874 -0.4064)
			(stroke
				(width 0.1524)
				(type default)
			)
			(layer "F.SilkS")
		)
		(fp_line
			(start 0.7874 -0.4064)
			(end 0.7874 0.4064)
			(stroke
				(width 0.1524)
				(type default)
			)
			(layer "F.SilkS")
		)
		(fp_line
			(start -0.67945 0.3048)
			(end -0.67945 -0.305054)
			(stroke
				(width 0.1)
				(type default)
			)
			(layer "F.Fab")
		)
		(fp_line
			(start -0.12065 0.3048)
			(end -0.67945 0.3048)
			(stroke
				(width 0.1)
				(type default)
			)
			(layer "F.Fab")
		)
		(fp_line
			(start 0.120396 0.3048)
			(end 0.120396 0.2794)
			(stroke
				(width 0.1)
				(type default)
			)
			(layer "F.Fab")
		)
		(fp_line
			(start 0.67945 0.3048)
			(end 0.120396 0.3048)
			(stroke
				(width 0.1)
				(type default)
			)
			(layer "F.Fab")
		)
		(fp_line
			(start -0.12065 0.2794)
			(end -0.12065 0.3048)
			(stroke
				(width 0.1)
				(type default)
			)
			(layer "F.Fab")
		)
		(fp_line
			(start 0.120396 0.2794)
			(end -0.12065 0.2794)
			(stroke
				(width 0.1)
				(type default)
			)
			(layer "F.Fab")
		)
		(fp_line
			(start -0.12065 -0.2794)
			(end 0.12065 -0.2794)
			(stroke
				(width 0.1)
				(type default)
			)
			(layer "F.Fab")
		)
		(fp_line
			(start 0.12065 -0.2794)
			(end 0.12065 -0.3048)
			(stroke
				(width 0.1)
				(type default)
			)
			(layer "F.Fab")
		)
		(fp_line
			(start 0.12065 -0.3048)
			(end 0.67945 -0.3048)
			(stroke
				(width 0.1)
				(type default)
			)
			(layer "F.Fab")
		)
		(fp_line
			(start 0.67945 -0.3048)
			(end 0.67945 0.3048)
			(stroke
				(width 0.1)
				(type default)
			)
			(layer "F.Fab")
		)
		(fp_line
			(start -0.67945 -0.305054)
			(end -0.12065 -0.305054)
			(stroke
				(width 0.1)
				(type default)
			)
			(layer "F.Fab")
		)
		(fp_line
			(start -0.12065 -0.305054)
			(end -0.12065 -0.2794)
			(stroke
				(width 0.1)
				(type default)
			)
			(layer "F.Fab")
		)
		(pad "1" smd circle
			(at -0.40005 0 270)
			(size 0 0)
			(layers "F.Cu" "F.Mask" "F.Paste")
			(net "PWRGD_P3V3_RGM_R")
		)
		(pad "2" smd circle
			(at 0.40005 0 270)
			(size 0 0)
			(layers "F.Cu" "F.Mask" "F.Paste")
			(net "PWRGD_P3V3_RGM")
		)
	)
	(footprint ""
		(layer "F.Cu")
		(at 39.22776 -61.6585)
		(property "Reference" "R479"
			(at 0 0 0)
			(layer "F.SilkS")
			(hide yes)
			(effects
				(font
					(size 1.27 1.27)
				)
			)
		)
		(property "Value" ""
			(at 0 0 0)
			(layer "F.Fab")
			(effects
				(font
					(size 1.27 1.27)
				)
			)
		)
		(duplicate_pad_numbers_are_jumpers no)
		(fp_line
			(start -0.7874 -0.4064)
			(end 0.7874 -0.4064)
			(stroke
				(width 0.1524)
				(type default)
			)
			(layer "F.SilkS")
		)
		(fp_line
			(start -0.7874 0.4064)
			(end -0.7874 -0.4064)
			(stroke
				(width 0.1524)
				(type default)
			)
			(layer "F.SilkS")
		)
		(fp_line
			(start 0.7874 -0.4064)
			(end 0.7874 0.4064)
			(stroke
				(width 0.1524)
				(type default)
			)
			(layer "F.SilkS")
		)
		(fp_line
			(start 0.7874 0.4064)
			(end -0.7874 0.4064)
			(stroke
				(width 0.1524)
				(type default)
			)
			(layer "F.SilkS")
		)
		(fp_line
			(start -0.67945 -0.305054)
			(end -0.12065 -0.305054)
			(stroke
				(width 0.1)
				(type default)
			)
			(layer "F.Fab")
		)
		(fp_line
			(start -0.67945 0.3048)
			(end -0.67945 -0.305054)
			(stroke
				(width 0.1)
				(type default)
			)
			(layer "F.Fab")
		)
		(fp_line
			(start -0.12065 -0.305054)
			(end -0.12065 -0.2794)
			(stroke
				(width 0.1)
				(type default)
			)
			(layer "F.Fab")
		)
		(fp_line
			(start -0.12065 -0.2794)
			(end 0.12065 -0.2794)
			(stroke
				(width 0.1)
				(type default)
			)
			(layer "F.Fab")
		)
		(fp_line
			(start -0.12065 0.2794)
			(end -0.12065 0.3048)
			(stroke
				(width 0.1)
				(type default)
			)
			(layer "F.Fab")
		)
		(fp_line
			(start -0.12065 0.3048)
			(end -0.67945 0.3048)
			(stroke
				(width 0.1)
				(type default)
			)
			(layer "F.Fab")
		)
		(fp_line
			(start 0.120396 0.2794)
			(end -0.12065 0.2794)
			(stroke
				(width 0.1)
				(type default)
			)
			(layer "F.Fab")
		)
		(fp_line
			(start 0.120396 0.3048)
			(end 0.120396 0.2794)
			(stroke
				(width 0.1)
				(type default)
			)
			(layer "F.Fab")
		)
		(fp_line
			(start 0.12065 -0.3048)
			(end 0.67945 -0.3048)
			(stroke
				(width 0.1)
				(type default)
			)
			(layer "F.Fab")
		)
		(fp_line
			(start 0.12065 -0.2794)
			(end 0.12065 -0.3048)
			(stroke
				(width 0.1)
				(type default)
			)
			(layer "F.Fab")
		)
		(fp_line
			(start 0.67945 -0.3048)
			(end 0.67945 0.3048)
			(stroke
				(width 0.1)
				(type default)
			)
			(layer "F.Fab")
		)
		(fp_line
			(start 0.67945 0.3048)
			(end 0.120396 0.3048)
			(stroke
				(width 0.1)
				(type default)
			)
			(layer "F.Fab")
		)
		(pad "1" smd circle
			(at -0.40005 0)
			(size 0 0)
			(layers "F.Cu" "F.Mask" "F.Paste")
			(net "FM_P12V_HSC_ENABLE")
		)
		(pad "2" smd circle
			(at 0.40005 0)
			(size 0 0)
			(layers "F.Cu" "F.Mask" "F.Paste")
			(net "FM_P12V_HSC_ENABLE_R1")
		)
	)
)
